(kicad_pcb
	(version 20260206)
	(generator "pcbnew")
	(generator_version "10.0")
	(general
		(thickness 1.6)
		(legacy_teardrops no)
	)
	(paper "A4")
	(title_block
		(title "Bryce Canyon_IOM_IOC_16318-2_OCP.brd")
		(comment 1 "Bryce Canyon / footprints 484-491 of 1605")
	)
	(layers
		(0 "F.Cu" signal "TOP")
		(4 "In1.Cu" signal "L2GND")
		(6 "In2.Cu" signal "L3")
		(8 "In3.Cu" signal "L4VCC")
		(10 "In4.Cu" signal "L5VCC")
		(12 "In5.Cu" signal "L6")
		(14 "In6.Cu" signal "L7GND")
		(2 "B.Cu" signal "BOTTOM")
		(9 "F.Adhes" user "F.Adhesive")
		(11 "B.Adhes" user "B.Adhesive")
		(13 "F.Paste" user "Package Geometry/Pastemask Top")
		(15 "B.Paste" user "Package Geometry/Pastemask Bottom")
		(5 "F.SilkS" user "Ref Des/Silkscreen Top")
		(7 "B.SilkS" user "Ref Des/Silkscreen Bottom")
		(1 "F.Mask" user "Board Geometry/Soldermask Top")
		(3 "B.Mask" user "Board Geometry/Soldermask Bottom")
		(17 "Dwgs.User" user "User.Drawings")
		(19 "Cmts.User" user "User.Comments")
		(21 "Eco1.User" user "User.Eco1")
		(23 "Eco2.User" user "User.Eco2")
		(25 "Edge.Cuts" user "Board Geometry/Outline")
		(27 "Margin" user)
		(31 "F.CrtYd" user "Package Geometry/Place Bound Top")
		(29 "B.CrtYd" user "Package Geometry/Place Bound Bottom")
		(35 "F.Fab" user "Ref Des/Assembly Top")
		(33 "B.Fab" user "Ref Des/Assembly Bottom")
	)
	(footprint ""
		(layer "F.Cu")
		(at 82.94116 -155.321 90)
		(property "Reference" "C236"
			(at 0 0 90)
			(layer "F.SilkS")
			(hide yes)
			(effects
				(font
					(size 1.27 1.27)
				)
			)
		)
		(property "Value" "SC10U6D3V5KX-4GP"
			(at -0.0762 -6.1214 90)
			(unlocked yes)
			(layer "F.Fab")
			(hide yes)
			(effects
				(font
					(size 1.016 1.016)
					(thickness 0.1524)
				)
			)
		)
		(property "Device Type" "C805H58"
			(at -0.0762 -8.1534 90)
			(unlocked yes)
			(layer "F.Fab")
			(hide yes)
			(effects
				(font
					(size 1.016 1.016)
					(thickness 0.1524)
				)
			)
		)
		(duplicate_pad_numbers_are_jumpers no)
		(fp_line
			(start 0.635 0)
			(end -0.635 0)
			(stroke
				(width 0.508)
				(type default)
			)
			(layer "F.SilkS")
		)
		(fp_rect
			(start -0.9652 1.778)
			(end 0.9652 -1.778)
			(stroke
				(width 0)
				(type default)
			)
			(fill no)
			(layer "F.CrtYd")
		)
		(fp_poly
			(pts
				(xy -0.9652 -1.778) (xy 0.9652 -1.778) (xy 0.9652 1.778) (xy -0.9652 1.778)
			)
			(stroke
				(width 0)
				(type default)
			)
			(fill no)
			(layer "F.Fab")
		)
		(pad "1" smd rect
			(at 0 -0.9652 90)
			(size 1.397 1.143)
			(layers "F.Cu" "F.Mask" "F.Paste")
			(net "TPS74801_P1V15_STBY_OUT")
		)
		(pad "2" smd rect
			(at 0 0.9652 90)
			(size 1.397 1.143)
			(layers "F.Cu" "F.Mask" "F.Paste")
			(net "GND")
		)
	)
	(footprint ""
		(layer "F.Cu")
		(at 23.368 -130.9878 180)
		(property "Reference" "R214"
			(at 0 0 180)
			(layer "F.SilkS")
			(hide yes)
			(effects
				(font
					(size 1.27 1.27)
				)
			)
		)
		(property "Value" "2K7R2F-GP"
			(at 0.064008 -3.993896 180)
			(unlocked yes)
			(layer "F.Fab")
			(hide yes)
			(effects
				(font
					(size 1.016 1.016)
					(thickness 0.1524)
				)
			)
		)
		(property "Device Type" "R402H16"
			(at 0.064008 -5.517896 180)
			(unlocked yes)
			(layer "F.Fab")
			(hide yes)
			(effects
				(font
					(size 1.016 1.016)
					(thickness 0.1524)
				)
			)
		)
		(duplicate_pad_numbers_are_jumpers no)
		(fp_line
			(start 0.508 -0.9398)
			(end -0.508 -0.9398)
			(stroke
				(width 0.1524)
				(type default)
			)
			(layer "F.SilkS")
		)
		(fp_line
			(start -0.508 -0.9398)
			(end -0.508 0.9398)
			(stroke
				(width 0.1524)
				(type default)
			)
			(layer "F.SilkS")
		)
		(fp_rect
			(start -0.508 0.9398)
			(end 0.508 -0.9398)
			(stroke
				(width 0)
				(type default)
			)
			(fill no)
			(layer "F.CrtYd")
		)
		(fp_rect
			(start -0.508 0.9398)
			(end 0.508 -0.9398)
			(stroke
				(width 0)
				(type default)
			)
			(fill no)
			(layer "F.Fab")
		)
		(pad "1" smd custom
			(at 0 -0.4445 180)
			(size 0.1397 0.1397)
			(layers "F.Cu" "F.Mask" "F.Paste")
			(net "DDR4_ALERT")
			(options
				(clearance outline)
				(anchor circle)
			)
			(primitives
				(gr_poly
					(pts
						(arc
							(start -0.1778 -0.2794)
							(mid -0.249642 -0.249642)
							(end -0.2794 -0.1778)
						)
						(arc
							(start -0.2794 0.1778)
							(mid -0.249642 0.249642)
							(end -0.1778 0.2794)
						)
						(arc
							(start 0.1778 0.2794)
							(mid 0.249642 0.249642)
							(end 0.2794 0.1778)
						)
						(arc
							(start 0.2794 -0.1778)
							(mid 0.249642 -0.249642)
							(end 0.1778 -0.2794)
						)
					)
					(width 0)
					(fill yes)
				)
			)
		)
		(pad "2" smd custom
			(at 0 0.4445 180)
			(size 0.1397 0.1397)
			(layers "F.Cu" "F.Mask" "F.Paste")
			(net "P1V2_STBY")
			(options
				(clearance outline)
				(anchor circle)
			)
			(primitives
				(gr_poly
					(pts
						(arc
							(start -0.1778 -0.2794)
							(mid -0.249642 -0.249642)
							(end -0.2794 -0.1778)
						)
						(arc
							(start -0.2794 0.1778)
							(mid -0.249642 0.249642)
							(end -0.1778 0.2794)
						)
						(arc
							(start 0.1778 0.2794)
							(mid 0.249642 0.249642)
							(end 0.2794 0.1778)
						)
						(arc
							(start 0.2794 -0.1778)
							(mid 0.249642 -0.249642)
							(end 0.1778 -0.2794)
						)
					)
					(width 0)
					(fill yes)
				)
			)
		)
	)
	(footprint ""
		(layer "F.Cu")
		(at 164.13988 -100.391976)
		(property "Reference" "Q15"
			(at 0 0 0)
			(layer "F.SilkS")
			(hide yes)
			(effects
				(font
					(size 1.27 1.27)
				)
			)
		)
		(property "Value" "SSM3K324R-GP"
			(at 0.127 -8.9662 0)
			(unlocked yes)
			(layer "F.Fab")
			(hide yes)
			(effects
				(font
					(size 1.016 1.016)
					(thickness 0.1524)
				)
			)
		)
		(property "Device Type" "SOT23DGS2D4H35"
			(at 0.127 -10.4902 0)
			(unlocked yes)
			(layer "F.Fab")
			(hide yes)
			(effects
				(font
					(size 1.016 1.016)
					(thickness 0.1524)
				)
			)
		)
		(duplicate_pad_numbers_are_jumpers no)
		(fp_line
			(start -1.651 -1.778)
			(end -1.651 1.778)
			(stroke
				(width 0.1524)
				(type default)
			)
			(layer "F.SilkS")
		)
		(fp_line
			(start -1.651 1.778)
			(end 1.651 1.778)
			(stroke
				(width 0.1524)
				(type default)
			)
			(layer "F.SilkS")
		)
		(fp_line
			(start 1.651 -1.778)
			(end -1.651 -1.778)
			(stroke
				(width 0.1524)
				(type default)
			)
			(layer "F.SilkS")
		)
		(fp_line
			(start 1.651 1.778)
			(end 1.651 -1.778)
			(stroke
				(width 0.1524)
				(type default)
			)
			(layer "F.SilkS")
		)
		(fp_poly
			(pts
				(xy -1.778 1.8796) (xy -1.778 -1.8796) (xy 1.778 -1.8796) (xy 1.778 1.8796)
			)
			(stroke
				(width 0)
				(type default)
			)
			(fill no)
			(layer "F.CrtYd")
		)
		(fp_poly
			(pts
				(xy -1.778 1.8796) (xy -1.778 -1.8796) (xy 1.778 -1.8796) (xy 1.778 1.8796)
			)
			(stroke
				(width 0)
				(type default)
			)
			(fill no)
			(layer "F.Fab")
		)
		(pad "D" smd custom
			(at 0 -0.9525)
			(size 0.1905 0.1905)
			(layers "F.Cu" "F.Mask" "F.Paste")
			(net "SYS_HB_LED_D")
			(options
				(clearance outline)
				(anchor circle)
			)
			(primitives
				(gr_poly
					(pts
						(arc
							(start -0.1778 0.5715)
							(mid -0.321484 0.511984)
							(end -0.381 0.3683)
						)
						(arc
							(start -0.381 -0.3683)
							(mid -0.321484 -0.511984)
							(end -0.1778 -0.5715)
						)
						(arc
							(start 0.1778 -0.5715)
							(mid 0.321484 -0.511984)
							(end 0.381 -0.3683)
						)
						(arc
							(start 0.381 0.3683)
							(mid 0.321484 0.511984)
							(end 0.1778 0.5715)
						)
					)
					(width 0)
					(fill yes)
				)
			)
		)
		(pad "G" smd custom
			(at -0.98425 0.9525)
			(size 0.1905 0.1905)
			(layers "F.Cu" "F.Mask" "F.Paste")
			(net "SYS_HB_LED")
			(options
				(clearance outline)
				(anchor circle)
			)
			(primitives
				(gr_poly
					(pts
						(arc
							(start -0.1778 0.5715)
							(mid -0.321484 0.511984)
							(end -0.381 0.3683)
						)
						(arc
							(start -0.381 -0.3683)
							(mid -0.321484 -0.511984)
							(end -0.1778 -0.5715)
						)
						(arc
							(start 0.1778 -0.5715)
							(mid 0.321484 -0.511984)
							(end 0.381 -0.3683)
						)
						(arc
							(start 0.381 0.3683)
							(mid 0.321484 0.511984)
							(end 0.1778 0.5715)
						)
					)
					(width 0)
					(fill yes)
				)
			)
		)
		(pad "S" smd custom
			(at 0.98425 0.9525)
			(size 0.1905 0.1905)
			(layers "F.Cu" "F.Mask" "F.Paste")
			(net "GND")
			(options
				(clearance outline)
				(anchor circle)
			)
			(primitives
				(gr_poly
					(pts
						(arc
							(start -0.1778 0.5715)
							(mid -0.321484 0.511984)
							(end -0.381 0.3683)
						)
						(arc
							(start -0.381 -0.3683)
							(mid -0.321484 -0.511984)
							(end -0.1778 -0.5715)
						)
						(arc
							(start 0.1778 -0.5715)
							(mid 0.321484 -0.511984)
							(end 0.381 -0.3683)
						)
						(arc
							(start 0.381 0.3683)
							(mid 0.321484 0.511984)
							(end 0.1778 0.5715)
						)
					)
					(width 0)
					(fill yes)
				)
			)
		)
	)
	(footprint ""
		(layer "F.Cu")
		(at 162.31616 -40.49014 180)
		(property "Reference" "R44"
			(at 0 0 180)
			(layer "F.SilkS")
			(hide yes)
			(effects
				(font
					(size 1.27 1.27)
				)
			)
		)
		(property "Value" "1MR2F-GP"
			(at 0.064008 -3.993896 180)
			(unlocked yes)
			(layer "F.Fab")
			(hide yes)
			(effects
				(font
					(size 1.016 1.016)
					(thickness 0.1524)
				)
			)
		)
		(property "Device Type" "R402H16"
			(at 0.064008 -5.517896 180)
			(unlocked yes)
			(layer "F.Fab")
			(hide yes)
			(effects
				(font
					(size 1.016 1.016)
					(thickness 0.1524)
				)
			)
		)
		(duplicate_pad_numbers_are_jumpers no)
		(fp_line
			(start 0.508 -0.9398)
			(end -0.508 -0.9398)
			(stroke
				(width 0.1524)
				(type default)
			)
			(layer "F.SilkS")
		)
		(fp_line
			(start -0.508 -0.9398)
			(end -0.508 0.9398)
			(stroke
				(width 0.1524)
				(type default)
			)
			(layer "F.SilkS")
		)
		(fp_rect
			(start -0.508 0.9398)
			(end 0.508 -0.9398)
			(stroke
				(width 0)
				(type default)
			)
			(fill no)
			(layer "F.CrtYd")
		)
		(fp_rect
			(start -0.508 0.9398)
			(end 0.508 -0.9398)
			(stroke
				(width 0)
				(type default)
			)
			(fill no)
			(layer "F.Fab")
		)
		(pad "1" smd custom
			(at 0 -0.4445 180)
			(size 0.1397 0.1397)
			(layers "F.Cu" "F.Mask" "F.Paste")
			(net "EXT2_CONN_GND")
			(options
				(clearance outline)
				(anchor circle)
			)
			(primitives
				(gr_poly
					(pts
						(arc
							(start -0.1778 -0.2794)
							(mid -0.249642 -0.249642)
							(end -0.2794 -0.1778)
						)
						(arc
							(start -0.2794 0.1778)
							(mid -0.249642 0.249642)
							(end -0.1778 0.2794)
						)
						(arc
							(start 0.1778 0.2794)
							(mid 0.249642 0.249642)
							(end 0.2794 0.1778)
						)
						(arc
							(start 0.2794 -0.1778)
							(mid 0.249642 -0.249642)
							(end 0.1778 -0.2794)
						)
					)
					(width 0)
					(fill yes)
				)
			)
		)
		(pad "2" smd custom
			(at 0 0.4445 180)
			(size 0.1397 0.1397)
			(layers "F.Cu" "F.Mask" "F.Paste")
			(net "GND")
			(options
				(clearance outline)
				(anchor circle)
			)
			(primitives
				(gr_poly
					(pts
						(arc
							(start -0.1778 -0.2794)
							(mid -0.249642 -0.249642)
							(end -0.2794 -0.1778)
						)
						(arc
							(start -0.2794 0.1778)
							(mid -0.249642 0.249642)
							(end -0.1778 0.2794)
						)
						(arc
							(start 0.1778 0.2794)
							(mid 0.249642 0.249642)
							(end 0.2794 0.1778)
						)
						(arc
							(start 0.2794 -0.1778)
							(mid 0.249642 -0.249642)
							(end 0.1778 -0.2794)
						)
					)
					(width 0)
					(fill yes)
				)
			)
		)
	)
	(footprint ""
		(layer "F.Cu")
		(at 79.98968 -172.90288)
		(property "Reference" "C195"
			(at 0 0 0)
			(layer "F.SilkS")
			(hide yes)
			(effects
				(font
					(size 1.27 1.27)
				)
			)
		)
		(property "Value" "SCD1U16V2KX-3GP"
			(at 1.1811 -2.7051 0)
			(unlocked yes)
			(layer "F.Fab")
			(hide yes)
			(effects
				(font
					(size 1.016 1.016)
					(thickness 0.1524)
				)
			)
		)
		(property "Device Type" "C402H22"
			(at 1.1811 -4.2291 0)
			(unlocked yes)
			(layer "F.Fab")
			(hide yes)
			(effects
				(font
					(size 1.016 1.016)
					(thickness 0.1524)
				)
			)
		)
		(duplicate_pad_numbers_are_jumpers no)
		(fp_rect
			(start -0.4318 0.9525)
			(end 0.4318 -0.9525)
			(stroke
				(width 0)
				(type default)
			)
			(fill no)
			(layer "F.CrtYd")
		)
		(fp_rect
			(start -0.4318 0.9525)
			(end 0.4318 -0.9525)
			(stroke
				(width 0)
				(type default)
			)
			(fill no)
			(layer "F.Fab")
		)
		(pad "1" smd custom
			(at 0 -0.4445)
			(size 0.1524 0.1524)
			(layers "F.Cu" "F.Mask" "F.Paste")
			(net "TPS74801_P2V5_STBY_OUT")
			(options
				(clearance outline)
				(anchor circle)
			)
			(primitives
				(gr_poly
					(pts
						(arc
							(start 0.3048 -0.2032)
							(mid 0.275042 -0.275042)
							(end 0.2032 -0.3048)
						)
						(arc
							(start -0.2032 -0.3048)
							(mid -0.275042 -0.275042)
							(end -0.3048 -0.2032)
						)
						(arc
							(start -0.3048 0.2032)
							(mid -0.275042 0.275042)
							(end -0.2032 0.3048)
						)
						(arc
							(start 0.2032 0.3048)
							(mid 0.275042 0.275042)
							(end 0.3048 0.2032)
						)
					)
					(width 0)
					(fill yes)
				)
			)
		)
		(pad "2" smd custom
			(at 0 0.4445)
			(size 0.1524 0.1524)
			(layers "F.Cu" "F.Mask" "F.Paste")
			(net "GND")
			(options
				(clearance outline)
				(anchor circle)
			)
			(primitives
				(gr_poly
					(pts
						(arc
							(start 0.3048 -0.2032)
							(mid 0.275042 -0.275042)
							(end 0.2032 -0.3048)
						)
						(arc
							(start -0.2032 -0.3048)
							(mid -0.275042 -0.275042)
							(end -0.3048 -0.2032)
						)
						(arc
							(start -0.3048 0.2032)
							(mid -0.275042 0.275042)
							(end -0.2032 0.3048)
						)
						(arc
							(start 0.2032 0.3048)
							(mid 0.275042 0.275042)
							(end 0.3048 0.2032)
						)
					)
					(width 0)
					(fill yes)
				)
			)
		)
	)
	(footprint ""
		(layer "F.Cu")
		(at 172.586904 -147.211034 90)
		(property "Reference" "R469"
			(at 0 0 90)
			(layer "F.SilkS")
			(hide yes)
			(effects
				(font
					(size 1.27 1.27)
				)
			)
		)
		(property "Value" "3D01R5F-GP"
			(at 0 -8.9535 90)
			(unlocked yes)
			(layer "F.Fab")
			(hide yes)
			(effects
				(font
					(size 1.27 1.016)
					(thickness 0.1524)
				)
			)
		)
		(property "Device Type" "R805H24"
			(at 0 -10.6299 90)
			(unlocked yes)
			(layer "F.Fab")
			(hide yes)
			(effects
				(font
					(size 1.27 1.016)
					(thickness 0.1524)
				)
			)
		)
		(duplicate_pad_numbers_are_jumpers no)
		(fp_line
			(start 0.889 -1.7018)
			(end -0.889 -1.7018)
			(stroke
				(width 0.1524)
				(type default)
			)
			(layer "F.SilkS")
		)
		(fp_line
			(start 0.889 -1.7018)
			(end 0.889 -0.381)
			(stroke
				(width 0.1524)
				(type default)
			)
			(layer "F.SilkS")
		)
		(fp_line
			(start -0.889 -1.7018)
			(end -0.889 0.2794)
			(stroke
				(width 0.1524)
				(type default)
			)
			(layer "F.SilkS")
		)
		(fp_line
			(start -0.889 0.0762)
			(end -0.889 1.7018)
			(stroke
				(width 0.1524)
				(type default)
			)
			(layer "F.SilkS")
		)
		(fp_line
			(start 0.889 1.7018)
			(end 0.889 -0.508)
			(stroke
				(width 0.1524)
				(type default)
			)
			(layer "F.SilkS")
		)
		(fp_line
			(start -0.889 1.7018)
			(end 0.889 1.7018)
			(stroke
				(width 0.1524)
				(type default)
			)
			(layer "F.SilkS")
		)
		(fp_poly
			(pts
				(xy 0.9652 -1.778) (xy 0.9652 1.778) (xy -0.9652 1.778) (xy -0.9652 -1.778)
			)
			(stroke
				(width 0)
				(type default)
			)
			(fill no)
			(layer "F.CrtYd")
		)
		(fp_rect
			(start -0.9652 1.778)
			(end 0.9652 -1.778)
			(stroke
				(width 0)
				(type default)
			)
			(fill no)
			(layer "F.Fab")
		)
		(pad "1" smd rect
			(at 0 -0.9652 90)
			(size 1.397 1.143)
			(layers "F.Cu" "F.Mask" "F.Paste")
			(net "P5V_SNB")
		)
		(pad "2" smd rect
			(at 0 0.9652 90)
			(size 1.397 1.143)
			(layers "F.Cu" "F.Mask" "F.Paste")
			(net "GND")
		)
	)
	(footprint ""
		(layer "F.Cu")
		(at 60.375546 -182.561738 -90)
		(property "Reference" "R481"
			(at 0 0 270)
			(layer "F.SilkS")
			(hide yes)
			(effects
				(font
					(size 1.27 1.27)
				)
			)
		)
		(property "Value" "0R6J-3-GP"
			(at -0.0508 -4.8514 270)
			(unlocked yes)
			(layer "F.Fab")
			(hide yes)
			(effects
				(font
					(size 1.016 1.016)
					(thickness 0.1524)
				)
			)
		)
		(property "Device Type" "R1206H28"
			(at 0 -6.3754 270)
			(unlocked yes)
			(layer "F.Fab")
			(hide yes)
			(effects
				(font
					(size 1.016 1.016)
					(thickness 0.1524)
				)
			)
		)
		(duplicate_pad_numbers_are_jumpers no)
		(fp_line
			(start -1.016 2.2352)
			(end -1.016 -2.2352)
			(stroke
				(width 0.1524)
				(type default)
			)
			(layer "F.SilkS")
		)
		(fp_line
			(start 1.016 2.2352)
			(end -1.016 2.2352)
			(stroke
				(width 0.1524)
				(type default)
			)
			(layer "F.SilkS")
		)
		(fp_line
			(start -1.016 -2.2352)
			(end 1.016 -2.2352)
			(stroke
				(width 0.1524)
				(type default)
			)
			(layer "F.SilkS")
		)
		(fp_line
			(start 1.016 -2.2352)
			(end 1.016 2.2352)
			(stroke
				(width 0.1524)
				(type default)
			)
			(layer "F.SilkS")
		)
		(fp_rect
			(start -1.0922 2.3114)
			(end 1.0922 -2.3114)
			(stroke
				(width 0)
				(type default)
			)
			(fill no)
			(layer "F.CrtYd")
		)
		(fp_poly
			(pts
				(xy -1.0922 -2.3114) (xy 1.0922 -2.3114) (xy 1.0922 2.3114) (xy -1.0922 2.3114)
			)
			(stroke
				(width 0)
				(type default)
			)
			(fill no)
			(layer "F.Fab")
		)
		(pad "1" smd rect
			(at 0 -1.397 270)
			(size 1.651 1.27)
			(layers "F.Cu" "F.Mask" "F.Paste")
			(net "P3V3_STBY")
		)
		(pad "2" smd rect
			(at 0 1.397 270)
			(size 1.651 1.27)
			(layers "F.Cu" "F.Mask" "F.Paste")
			(net "P3V3_STBY_OUT")
		)
	)
	(footprint ""
		(layer "F.Cu")
		(at 197.5358 -19.2786 180)
		(property "Reference" "R696"
			(at 0 0 180)
			(layer "F.SilkS")
			(hide yes)
			(effects
				(font
					(size 1.27 1.27)
				)
			)
		)
		(property "Value" "1KR2F-3-GP"
			(at 0.064008 -3.993896 180)
			(unlocked yes)
			(layer "F.Fab")
			(hide yes)
			(effects
				(font
					(size 1.016 1.016)
					(thickness 0.1524)
				)
			)
		)
		(property "Device Type" "R402H16"
			(at 0.064008 -5.517896 180)
			(unlocked yes)
			(layer "F.Fab")
			(hide yes)
			(effects
				(font
					(size 1.016 1.016)
					(thickness 0.1524)
				)
			)
		)
		(duplicate_pad_numbers_are_jumpers no)
		(fp_line
			(start 0.508 -0.9398)
			(end -0.508 -0.9398)
			(stroke
				(width 0.1524)
				(type default)
			)
			(layer "F.SilkS")
		)
		(fp_line
			(start -0.508 -0.9398)
			(end -0.508 0.9398)
			(stroke
				(width 0.1524)
				(type default)
			)
			(layer "F.SilkS")
		)
		(fp_rect
			(start -0.508 0.9398)
			(end 0.508 -0.9398)
			(stroke
				(width 0)
				(type default)
			)
			(fill no)
			(layer "F.CrtYd")
		)
		(fp_rect
			(start -0.508 0.9398)
			(end 0.508 -0.9398)
			(stroke
				(width 0)
				(type default)
			)
			(fill no)
			(layer "F.Fab")
		)
		(pad "1" smd custom
			(at 0 -0.4445 180)
			(size 0.1397 0.1397)
			(layers "F.Cu" "F.Mask" "F.Paste")
			(net "P3V3_STBY")
			(options
				(clearance outline)
				(anchor circle)
			)
			(primitives
				(gr_poly
					(pts
						(arc
							(start -0.1778 -0.2794)
							(mid -0.249642 -0.249642)
							(end -0.2794 -0.1778)
						)
						(arc
							(start -0.2794 0.1778)
							(mid -0.249642 0.249642)
							(end -0.1778 0.2794)
						)
						(arc
							(start 0.1778 0.2794)
							(mid 0.249642 0.249642)
							(end 0.2794 0.1778)
						)
						(arc
							(start 0.2794 -0.1778)
							(mid 0.249642 -0.249642)
							(end 0.1778 -0.2794)
						)
					)
					(width 0)
					(fill yes)
				)
			)
		)
		(pad "2" smd custom
			(at 0 0.4445 180)
			(size 0.1397 0.1397)
			(layers "F.Cu" "F.Mask" "F.Paste")
			(net "EXT1_LED_YELLOW_D")
			(options
				(clearance outline)
				(anchor circle)
			)
			(primitives
				(gr_poly
					(pts
						(arc
							(start -0.1778 -0.2794)
							(mid -0.249642 -0.249642)
							(end -0.2794 -0.1778)
						)
						(arc
							(start -0.2794 0.1778)
							(mid -0.249642 0.249642)
							(end -0.1778 0.2794)
						)
						(arc
							(start 0.1778 0.2794)
							(mid 0.249642 0.249642)
							(end 0.2794 0.1778)
						)
						(arc
							(start 0.2794 -0.1778)
							(mid 0.249642 -0.249642)
							(end 0.1778 -0.2794)
						)
					)
					(width 0)
					(fill yes)
				)
			)
		)
	)
)
